#ISCELL
  pure_quanta quanta_title_block_c *
  *
#CELL
  pure_quanta genoa_sp5 *
  page23_i215
#CELL
  pure_quanta genoa_sp5 *
  page23_i216
#ISCELL
  standard offpage *
  page23_i217
#ISCELL
  standard offpage *
  page23_i218
#ISCELL
  mstr_standard tap *
  page23_i219
#ISCELL
  mstr_standard tap *
  page23_i220
#ISCELL
  mstr_standard tap *
  page23_i221
#ISCELL
  mstr_standard tap *
  page23_i222
#ISCELL
  standard tap *
  page23_i223
#ISCELL
  standard tap *
  page23_i224
#ISCELL
  standard tap *
  page23_i225
#ISCELL
  standard tap *
  page23_i226
#ISCELL
  standard tap *
  page23_i227
#ISCELL
  standard tap *
  page23_i228
#ISCELL
  standard tap *
  page23_i229
#ISCELL
  standard tap *
  page23_i230
#ISCELL
  standard tap *
  page23_i231
#ISCELL
  standard tap *
  page23_i232
#ISCELL
  standard tap *
  page23_i233
#ISCELL
  standard tap *
  page23_i234
#ISCELL
  standard tap *
  page23_i235
#ISCELL
  standard tap *
  page23_i236
#ISCELL
  standard tap *
  page23_i237
#ISCELL
  standard tap *
  page23_i238
#ISCELL
  standard tap *
  page23_i239
#ISCELL
  standard tap *
  page23_i240
#ISCELL
  standard tap *
  page23_i241
#ISCELL
  standard tap *
  page23_i242
#ISCELL
  standard tap *
  page23_i243
#ISCELL
  standard tap *
  page23_i244
#ISCELL
  standard tap *
  page23_i245
#ISCELL
  standard tap *
  page23_i246
#ISCELL
  standard tap *
  page23_i247
#ISCELL
  standard tap *
  page23_i248
#ISCELL
  standard tap *
  page23_i249
#ISCELL
  standard tap *
  page23_i250
#ISCELL
  mstr_standard tap *
  page23_i251
#ISCELL
  mstr_standard tap *
  page23_i252
#ISCELL
  mstr_standard tap *
  page23_i253
#ISCELL
  mstr_standard tap *
  page23_i254
#ISCELL
  standard tap *
  page23_i255
#ISCELL
  mstr_standard tap *
  page23_i256
#ISCELL
  standard tap *
  page23_i257
#ISCELL
  standard tap *
  page23_i258
#ISCELL
  standard tap *
  page23_i259
#ISCELL
  standard tap *
  page23_i260
#ISCELL
  standard tap *
  page23_i261
#ISCELL
  standard tap *
  page23_i262
#ISCELL
  standard tap *
  page23_i263
#ISCELL
  standard tap *
  page23_i264
#ISCELL
  standard tap *
  page23_i265
#ISCELL
  standard tap *
  page23_i266
#ISCELL
  standard tap *
  page23_i267
#ISCELL
  standard tap *
  page23_i268
#ISCELL
  standard tap *
  page23_i269
#ISCELL
  standard tap *
  page23_i270
#ISCELL
  standard tap *
  page23_i271
#ISCELL
  standard tap *
  page23_i272
#ISCELL
  standard tap *
  page23_i273
#ISCELL
  standard tap *
  page23_i274
#ISCELL
  standard tap *
  page23_i275
#ISCELL
  standard tap *
  page23_i276
#ISCELL
  standard tap *
  page23_i277
#ISCELL
  standard tap *
  page23_i278
#ISCELL
  standard tap *
  page23_i279
#ISCELL
  standard tap *
  page23_i280
#ISCELL
  standard tap *
  page23_i281
#ISCELL
  standard tap *
  page23_i282
#ISCELL
  standard offpage *
  page23_i283
#ISCELL
  standard offpage *
  page23_i284
#ISCELL
  standard tap *
  page23_i285
#ISCELL
  standard tap *
  page23_i286
#ISCELL
  standard tap *
  page23_i287
#ISCELL
  standard tap *
  page23_i288
#ISCELL
  standard tap *
  page23_i289
#ISCELL
  standard offpage *
  page23_i290
#ISCELL
  standard offpage *
  page23_i291
#ISCELL
  mstr_standard tap *
  page23_i292
#ISCELL
  mstr_standard tap *
  page23_i293
#ISCELL
  mstr_standard tap *
  page23_i294
#ISCELL
  standard tap *
  page23_i295
#ISCELL
  mstr_standard tap *
  page23_i296
#ISCELL
  standard tap *
  page23_i297
#ISCELL
  standard tap *
  page23_i298
#ISCELL
  standard tap *
  page23_i299
#ISCELL
  standard tap *
  page23_i300
#ISCELL
  standard tap *
  page23_i301
#ISCELL
  standard tap *
  page23_i302
#ISCELL
  standard tap *
  page23_i303
#ISCELL
  standard tap *
  page23_i304
#ISCELL
  standard tap *
  page23_i305
#ISCELL
  standard tap *
  page23_i306
#ISCELL
  standard tap *
  page23_i307
#ISCELL
  standard tap *
  page23_i308
#ISCELL
  standard tap *
  page23_i309
#ISCELL
  standard tap *
  page23_i310
#ISCELL
  standard tap *
  page23_i311
#ISCELL
  standard tap *
  page23_i312
#ISCELL
  standard tap *
  page23_i313
#ISCELL
  standard tap *
  page23_i314
#ISCELL
  standard tap *
  page23_i315
#ISCELL
  standard tap *
  page23_i316
#ISCELL
  standard tap *
  page23_i317
#ISCELL
  standard tap *
  page23_i318
#ISCELL
  mstr_standard tap *
  page23_i319
#ISCELL
  mstr_standard tap *
  page23_i320
#ISCELL
  mstr_standard tap *
  page23_i321
#ISCELL
  mstr_standard tap *
  page23_i322
#ISCELL
  standard tap *
  page23_i323
#ISCELL
  mstr_standard tap *
  page23_i324
#ISCELL
  standard tap *
  page23_i325
#ISCELL
  standard tap *
  page23_i326
#ISCELL
  standard tap *
  page23_i327
#ISCELL
  standard tap *
  page23_i328
#ISCELL
  standard tap *
  page23_i329
#ISCELL
  standard tap *
  page23_i330
#ISCELL
  standard tap *
  page23_i331
#ISCELL
  standard tap *
  page23_i332
#ISCELL
  standard tap *
  page23_i333
#ISCELL
  standard tap *
  page23_i334
#ISCELL
  standard tap *
  page23_i335
#ISCELL
  standard tap *
  page23_i336
#ISCELL
  standard tap *
  page23_i337
#ISCELL
  standard offpage *
  page23_i338
#ISCELL
  standard offpage *
  page23_i339
#ISCELL
  standard tap *
  page23_i340
#ISCELL
  standard tap *
  page23_i341
#ISCELL
  standard tap *
  page23_i342
#ISCELL
  standard tap *
  page23_i343
#ISCELL
  standard tap *
  page23_i344
#ISCELL
  standard tap *
  page23_i345
#ISCELL
  standard tap *
  page23_i346
#ISCELL
  standard tap *
  page23_i347
#ISCELL
  standard tap *
  page23_i348
#ISCELL
  standard tap *
  page23_i349
#ISCELL
  standard tap *
  page23_i350
#ISCELL
  standard tap *
  page23_i351
#ISCELL
  standard tap *
  page23_i352
